# S9S_MB_2U (Grand Teton) — schematic netlist excerpt (pin names and nets, part order shuffled) for the footprints in the layout excerpt that follows; sources: Cadence DE-HDL packaged netlist, KiCad conversion of 03242023_DA0F0TMBIJ0_F0T_Motherboard_J_brd_V01_OCP.brd

R4557  Q_RES  33.2 1% CHIP  pkg 0402LF  page 215 : A = HPDB_HSC_PWRGD_ISO ; B = HPDB_HSC_PWRGD_ISO_R
R4126  Q_RES  4.7K 5% CHIP  pkg 0402LF  page 146 : A = P3V3_AUX ; B = PRSNT_CABLE_GPU_B3

(kicad_pcb
	(version 20260206)
	(generator "pcbnew")
	(generator_version "10.0")
	(general
		(thickness 1.6)
		(legacy_teardrops no)
	)
	(paper "A4")
	(title_block
		(title "03242023_DA0F0TMBIJ0_F0T_Motherboard_J_brd_V01_OCP.brd")
		(comment 1 "Grand Teton / footprints 3350-3351 of 6105")
	)
	(layers
		(0 "F.Cu" signal "TOP")
		(4 "In1.Cu" signal "GND")
		(6 "In2.Cu" signal "IN1")
		(8 "In3.Cu" signal "GND1")
		(10 "In4.Cu" signal "IN2")
		(12 "In5.Cu" signal "GND2")
		(14 "In6.Cu" signal "IN3")
		(16 "In7.Cu" signal "GND3")
		(18 "In8.Cu" signal "VCC")
		(20 "In9.Cu" signal "VCC1")
		(22 "In10.Cu" signal "GND4")
		(24 "In11.Cu" signal "IN4")
		(26 "In12.Cu" signal "GND5")
		(28 "In13.Cu" signal "IN5")
		(30 "In14.Cu" signal "GND6")
		(32 "In15.Cu" signal "IN6")
		(34 "In16.Cu" signal "GND7")
		(2 "B.Cu" signal "BOTTOM")
		(9 "F.Adhes" user "F.Adhesive")
		(11 "B.Adhes" user "B.Adhesive")
		(13 "F.Paste" user "Package Geometry/Pastemask Top")
		(15 "B.Paste" user "Package Geometry/Pastemask Bottom")
		(5 "F.SilkS" user "Ref Des/Silkscreen Top")
		(7 "B.SilkS" user "Ref Des/Silkscreen Bottom")
		(1 "F.Mask" user "Board Geometry/Soldermask Top")
		(3 "B.Mask" user "Board Geometry/Soldermask Bottom")
		(17 "Dwgs.User" user "User.Drawings")
		(19 "Cmts.User" user "User.Comments")
		(21 "Eco1.User" user "User.Eco1")
		(23 "Eco2.User" user "User.Eco2")
		(25 "Edge.Cuts" user "Board Geometry/Outline")
		(27 "Margin" user)
		(31 "F.CrtYd" user "Package Geometry/Place Bound Top")
		(29 "B.CrtYd" user "Package Geometry/Place Bound Bottom")
		(35 "F.Fab" user "Ref Des/Assembly Top")
		(33 "B.Fab" user "Ref Des/Assembly Bottom")
	)
	(footprint ""
		(layer "F.Cu")
		(at 283.413708 -411.29458 -90)
		(property "Reference" "R4557"
			(at 0 0 270)
			(layer "F.SilkS")
			(hide yes)
			(effects
				(font
					(size 1.27 1.27)
				)
			)
		)
		(property "Value" ""
			(at 0 0 270)
			(layer "F.Fab")
			(effects
				(font
					(size 1.27 1.27)
				)
			)
		)
		(duplicate_pad_numbers_are_jumpers no)
		(fp_line
			(start -0.7874 0.4064)
			(end -0.7874 -0.4064)
			(stroke
				(width 0.1524)
				(type default)
			)
			(layer "F.SilkS")
		)
		(fp_line
			(start 0.7874 0.4064)
			(end -0.7874 0.4064)
			(stroke
				(width 0.1524)
				(type default)
			)
			(layer "F.SilkS")
		)
		(fp_line
			(start -0.7874 -0.4064)
			(end 0.7874 -0.4064)
			(stroke
				(width 0.1524)
				(type default)
			)
			(layer "F.SilkS")
		)
		(fp_line
			(start 0.7874 -0.4064)
			(end 0.7874 0.4064)
			(stroke
				(width 0.1524)
				(type default)
			)
			(layer "F.SilkS")
		)
		(fp_line
			(start -0.67945 0.3048)
			(end -0.67945 -0.305054)
			(stroke
				(width 0.1)
				(type default)
			)
			(layer "F.Fab")
		)
		(fp_line
			(start -0.12065 0.3048)
			(end -0.67945 0.3048)
			(stroke
				(width 0.1)
				(type default)
			)
			(layer "F.Fab")
		)
		(fp_line
			(start 0.120396 0.3048)
			(end 0.120396 0.2794)
			(stroke
				(width 0.1)
				(type default)
			)
			(layer "F.Fab")
		)
		(fp_line
			(start 0.67945 0.3048)
			(end 0.120396 0.3048)
			(stroke
				(width 0.1)
				(type default)
			)
			(layer "F.Fab")
		)
		(fp_line
			(start -0.12065 0.2794)
			(end -0.12065 0.3048)
			(stroke
				(width 0.1)
				(type default)
			)
			(layer "F.Fab")
		)
		(fp_line
			(start 0.120396 0.2794)
			(end -0.12065 0.2794)
			(stroke
				(width 0.1)
				(type default)
			)
			(layer "F.Fab")
		)
		(fp_line
			(start -0.12065 -0.2794)
			(end 0.12065 -0.2794)
			(stroke
				(width 0.1)
				(type default)
			)
			(layer "F.Fab")
		)
		(fp_line
			(start 0.12065 -0.2794)
			(end 0.12065 -0.3048)
			(stroke
				(width 0.1)
				(type default)
			)
			(layer "F.Fab")
		)
		(fp_line
			(start 0.12065 -0.3048)
			(end 0.67945 -0.3048)
			(stroke
				(width 0.1)
				(type default)
			)
			(layer "F.Fab")
		)
		(fp_line
			(start 0.67945 -0.3048)
			(end 0.67945 0.3048)
			(stroke
				(width 0.1)
				(type default)
			)
			(layer "F.Fab")
		)
		(fp_line
			(start -0.67945 -0.305054)
			(end -0.12065 -0.305054)
			(stroke
				(width 0.1)
				(type default)
			)
			(layer "F.Fab")
		)
		(fp_line
			(start -0.12065 -0.305054)
			(end -0.12065 -0.2794)
			(stroke
				(width 0.1)
				(type default)
			)
			(layer "F.Fab")
		)
		(pad "1" smd circle
			(at -0.40005 0 270)
			(size 0 0)
			(layers "F.Cu" "F.Mask" "F.Paste")
			(net "HPDB_HSC_PWRGD_ISO")
		)
		(pad "2" smd circle
			(at 0.40005 0 270)
			(size 0 0)
			(layers "F.Cu" "F.Mask" "F.Paste")
			(net "HPDB_HSC_PWRGD_ISO_R")
		)
	)
	(footprint ""
		(layer "F.Cu")
		(at 301.136304 -426.478446 -90)
		(property "Reference" "R4126"
			(at 0 0 270)
			(layer "F.SilkS")
			(hide yes)
			(effects
				(font
					(size 1.27 1.27)
				)
			)
		)
		(property "Value" ""
			(at 0 0 270)
			(layer "F.Fab")
			(effects
				(font
					(size 1.27 1.27)
				)
			)
		)
		(duplicate_pad_numbers_are_jumpers no)
		(fp_line
			(start -0.7874 0.4064)
			(end -0.7874 -0.4064)
			(stroke
				(width 0.1524)
				(type default)
			)
			(layer "F.SilkS")
		)
		(fp_line
			(start 0.7874 0.4064)
			(end -0.7874 0.4064)
			(stroke
				(width 0.1524)
				(type default)
			)
			(layer "F.SilkS")
		)
		(fp_line
			(start -0.7874 -0.4064)
			(end 0.7874 -0.4064)
			(stroke
				(width 0.1524)
				(type default)
			)
			(layer "F.SilkS")
		)
		(fp_line
			(start 0.7874 -0.4064)
			(end 0.7874 0.4064)
			(stroke
				(width 0.1524)
				(type default)
			)
			(layer "F.SilkS")
		)
		(fp_line
			(start -0.67945 0.3048)
			(end -0.67945 -0.305054)
			(stroke
				(width 0.1)
				(type default)
			)
			(layer "F.Fab")
		)
		(fp_line
			(start -0.12065 0.3048)
			(end -0.67945 0.3048)
			(stroke
				(width 0.1)
				(type default)
			)
			(layer "F.Fab")
		)
		(fp_line
			(start 0.120396 0.3048)
			(end 0.120396 0.2794)
			(stroke
				(width 0.1)
				(type default)
			)
			(layer "F.Fab")
		)
		(fp_line
			(start 0.67945 0.3048)
			(end 0.120396 0.3048)
			(stroke
				(width 0.1)
				(type default)
			)
			(layer "F.Fab")
		)
		(fp_line
			(start -0.12065 0.2794)
			(end -0.12065 0.3048)
			(stroke
				(width 0.1)
				(type default)
			)
			(layer "F.Fab")
		)
		(fp_line
			(start 0.120396 0.2794)
			(end -0.12065 0.2794)
			(stroke
				(width 0.1)
				(type default)
			)
			(layer "F.Fab")
		)
		(fp_line
			(start -0.12065 -0.2794)
			(end 0.12065 -0.2794)
			(stroke
				(width 0.1)
				(type default)
			)
			(layer "F.Fab")
		)
		(fp_line
			(start 0.12065 -0.2794)
			(end 0.12065 -0.3048)
			(stroke
				(width 0.1)
				(type default)
			)
			(layer "F.Fab")
		)
		(fp_line
			(start 0.12065 -0.3048)
			(end 0.67945 -0.3048)
			(stroke
				(width 0.1)
				(type default)
			)
			(layer "F.Fab")
		)
		(fp_line
			(start 0.67945 -0.3048)
			(end 0.67945 0.3048)
			(stroke
				(width 0.1)
				(type default)
			)
			(layer "F.Fab")
		)
		(fp_line
			(start -0.67945 -0.305054)
			(end -0.12065 -0.305054)
			(stroke
				(width 0.1)
				(type default)
			)
			(layer "F.Fab")
		)
		(fp_line
			(start -0.12065 -0.305054)
			(end -0.12065 -0.2794)
			(stroke
				(width 0.1)
				(type default)
			)
			(layer "F.Fab")
		)
		(pad "1" smd circle
			(at -0.40005 0 270)
			(size 0 0)
			(layers "F.Cu" "F.Mask" "F.Paste")
			(net "P3V3_AUX")
		)
		(pad "2" smd circle
			(at 0.40005 0 270)
			(size 0 0)
			(layers "F.Cu" "F.Mask" "F.Paste")
			(net "PRSNT_CABLE_GPU_B3")
		)
	)
)
